(kicad_pcb
	(version 20260206)
	(generator "pcbnew")
	(generator_version "10.0")
	(general
		(thickness 1.6)
		(legacy_teardrops no)
	)
	(paper "A4")
	(title_block
		(title "dpb — 14545-sa.0730WZS0815.brd")
		(comment 1 "Honey Badger (Wiwynn) / footprints 95-101 of 1066")
	)
	(layers
		(0 "F.Cu" signal "TOP")
		(4 "In1.Cu" signal "L2GND")
		(6 "In2.Cu" signal "L3")
		(8 "In3.Cu" signal "L4VCC")
		(10 "In4.Cu" signal "L5VCC")
		(12 "In5.Cu" signal "L6")
		(14 "In6.Cu" signal "L7GND")
		(2 "B.Cu" signal "BOTTOM")
		(9 "F.Adhes" user "F.Adhesive")
		(11 "B.Adhes" user "B.Adhesive")
		(13 "F.Paste" user "Package Geometry/Pastemask Top")
		(15 "B.Paste" user "Package Geometry/Pastemask Bottom")
		(5 "F.SilkS" user "Ref Des/Silkscreen Top")
		(7 "B.SilkS" user "Ref Des/Silkscreen Bottom")
		(1 "F.Mask" user "Board Geometry/Soldermask Top")
		(3 "B.Mask" user "Board Geometry/Soldermask Bottom")
		(17 "Dwgs.User" user "User.Drawings")
		(19 "Cmts.User" user "User.Comments")
		(21 "Eco1.User" user "User.Eco1")
		(23 "Eco2.User" user "User.Eco2")
		(25 "Edge.Cuts" user "Board Geometry/Outline")
		(27 "Margin" user)
		(31 "F.CrtYd" user "Package Geometry/Place Bound Top")
		(29 "B.CrtYd" user "Package Geometry/Place Bound Bottom")
		(35 "F.Fab" user "Ref Des/Assembly Top")
		(33 "B.Fab" user "Ref Des/Assembly Bottom")
	)
	(footprint ""
		(layer "F.Cu")
		(at 211.708746 -452.6407 180)
		(property "Reference" "R327"
			(at 0 0 180)
			(layer "F.SilkS")
			(hide yes)
			(effects
				(font
					(size 1.27 1.27)
				)
			)
		)
		(property "Value" "4K7R2J-2-GP"
			(at 0.064008 -3.993896 180)
			(unlocked yes)
			(layer "F.Fab")
			(hide yes)
			(effects
				(font
					(size 1.016 1.016)
					(thickness 0.1524)
				)
			)
		)
		(property "Device Type" "R402H16"
			(at 0.064008 -5.517896 180)
			(unlocked yes)
			(layer "F.Fab")
			(hide yes)
			(effects
				(font
					(size 1.016 1.016)
					(thickness 0.1524)
				)
			)
		)
		(duplicate_pad_numbers_are_jumpers no)
		(fp_line
			(start 0.508 -0.9398)
			(end -0.508 -0.9398)
			(stroke
				(width 0.1524)
				(type default)
			)
			(layer "F.SilkS")
		)
		(fp_line
			(start -0.508 -0.9398)
			(end -0.508 0.9398)
			(stroke
				(width 0.1524)
				(type default)
			)
			(layer "F.SilkS")
		)
		(fp_rect
			(start -0.508 0.9398)
			(end 0.508 -0.9398)
			(stroke
				(width 0)
				(type default)
			)
			(fill no)
			(layer "F.CrtYd")
		)
		(fp_rect
			(start -0.508 0.9398)
			(end 0.508 -0.9398)
			(stroke
				(width 0)
				(type default)
			)
			(fill no)
			(layer "F.Fab")
		)
		(pad "1" smd custom
			(at 0 -0.4445 180)
			(size 0.1397 0.1397)
			(layers "F.Cu" "F.Mask" "F.Paste")
			(net "P3V3")
			(options
				(clearance outline)
				(anchor circle)
			)
			(primitives
				(gr_poly
					(pts
						(arc
							(start -0.1778 -0.2794)
							(mid -0.249642 -0.249642)
							(end -0.2794 -0.1778)
						)
						(arc
							(start -0.2794 0.1778)
							(mid -0.249642 0.249642)
							(end -0.1778 0.2794)
						)
						(arc
							(start 0.1778 0.2794)
							(mid 0.249642 0.249642)
							(end 0.2794 0.1778)
						)
						(arc
							(start 0.2794 -0.1778)
							(mid 0.249642 -0.249642)
							(end 0.1778 -0.2794)
						)
					)
					(width 0)
					(fill yes)
				)
			)
		)
		(pad "2" smd custom
			(at 0 0.4445 180)
			(size 0.1397 0.1397)
			(layers "F.Cu" "F.Mask" "F.Paste")
			(net "I2C_B_TMP3_A0")
			(options
				(clearance outline)
				(anchor circle)
			)
			(primitives
				(gr_poly
					(pts
						(arc
							(start -0.1778 -0.2794)
							(mid -0.249642 -0.249642)
							(end -0.2794 -0.1778)
						)
						(arc
							(start -0.2794 0.1778)
							(mid -0.249642 0.249642)
							(end -0.1778 0.2794)
						)
						(arc
							(start 0.1778 0.2794)
							(mid 0.249642 0.249642)
							(end 0.2794 0.1778)
						)
						(arc
							(start 0.2794 -0.1778)
							(mid 0.249642 -0.249642)
							(end 0.1778 -0.2794)
						)
					)
					(width 0)
					(fill yes)
				)
			)
		)
	)
	(footprint ""
		(layer "F.Cu")
		(at 191.853058 -390.219184 -90)
		(property "Reference" "R127"
			(at 0 0 270)
			(layer "F.SilkS")
			(hide yes)
			(effects
				(font
					(size 1.27 1.27)
				)
			)
		)
		(property "Value" "0R2J-2-GP"
			(at 0.064008 -3.993896 270)
			(unlocked yes)
			(layer "F.Fab")
			(hide yes)
			(effects
				(font
					(size 1.016 1.016)
					(thickness 0.1524)
				)
			)
		)
		(property "Device Type" "R402H16"
			(at 0.064008 -5.517896 270)
			(unlocked yes)
			(layer "F.Fab")
			(hide yes)
			(effects
				(font
					(size 1.016 1.016)
					(thickness 0.1524)
				)
			)
		)
		(duplicate_pad_numbers_are_jumpers no)
		(fp_line
			(start -0.508 -0.9398)
			(end -0.508 0.9398)
			(stroke
				(width 0.1524)
				(type default)
			)
			(layer "F.SilkS")
		)
		(fp_line
			(start 0.508 -0.9398)
			(end -0.508 -0.9398)
			(stroke
				(width 0.1524)
				(type default)
			)
			(layer "F.SilkS")
		)
		(fp_rect
			(start -0.508 0.9398)
			(end 0.508 -0.9398)
			(stroke
				(width 0)
				(type default)
			)
			(fill no)
			(layer "F.CrtYd")
		)
		(fp_rect
			(start -0.508 0.9398)
			(end 0.508 -0.9398)
			(stroke
				(width 0)
				(type default)
			)
			(fill no)
			(layer "F.Fab")
		)
		(pad "1" smd custom
			(at 0 -0.4445 270)
			(size 0.1397 0.1397)
			(layers "F.Cu" "F.Mask" "F.Paste")
			(net "DRIVE_PWR1")
			(options
				(clearance outline)
				(anchor circle)
			)
			(primitives
				(gr_poly
					(pts
						(arc
							(start -0.1778 -0.2794)
							(mid -0.249642 -0.249642)
							(end -0.2794 -0.1778)
						)
						(arc
							(start -0.2794 0.1778)
							(mid -0.249642 0.249642)
							(end -0.1778 0.2794)
						)
						(arc
							(start 0.1778 0.2794)
							(mid 0.249642 0.249642)
							(end 0.2794 0.1778)
						)
						(arc
							(start 0.2794 -0.1778)
							(mid 0.249642 -0.249642)
							(end 0.1778 -0.2794)
						)
					)
					(width 0)
					(fill yes)
				)
			)
		)
		(pad "2" smd custom
			(at 0 0.4445 270)
			(size 0.1397 0.1397)
			(layers "F.Cu" "F.Mask" "F.Paste")
			(net "SW_PWR_HDD1")
			(options
				(clearance outline)
				(anchor circle)
			)
			(primitives
				(gr_poly
					(pts
						(arc
							(start -0.1778 -0.2794)
							(mid -0.249642 -0.249642)
							(end -0.2794 -0.1778)
						)
						(arc
							(start -0.2794 0.1778)
							(mid -0.249642 0.249642)
							(end -0.1778 0.2794)
						)
						(arc
							(start 0.1778 0.2794)
							(mid 0.249642 0.249642)
							(end 0.2794 0.1778)
						)
						(arc
							(start 0.2794 -0.1778)
							(mid 0.249642 -0.249642)
							(end 0.1778 -0.2794)
						)
					)
					(width 0)
					(fill yes)
				)
			)
		)
	)
	(footprint ""
		(layer "F.Cu")
		(at 39.750746 -41.9227 90)
		(property "Reference" "R227"
			(at 0 0 90)
			(layer "F.SilkS")
			(hide yes)
			(effects
				(font
					(size 1.27 1.27)
				)
			)
		)
		(property "Value" "402R2F-GP"
			(at 0.064008 -3.993896 90)
			(unlocked yes)
			(layer "F.Fab")
			(hide yes)
			(effects
				(font
					(size 1.016 1.016)
					(thickness 0.1524)
				)
			)
		)
		(property "Device Type" "R402H16"
			(at 0.064008 -5.517896 90)
			(unlocked yes)
			(layer "F.Fab")
			(hide yes)
			(effects
				(font
					(size 1.016 1.016)
					(thickness 0.1524)
				)
			)
		)
		(duplicate_pad_numbers_are_jumpers no)
		(fp_line
			(start 0.508 -0.9398)
			(end -0.508 -0.9398)
			(stroke
				(width 0.1524)
				(type default)
			)
			(layer "F.SilkS")
		)
		(fp_line
			(start -0.508 -0.9398)
			(end -0.508 0.9398)
			(stroke
				(width 0.1524)
				(type default)
			)
			(layer "F.SilkS")
		)
		(fp_rect
			(start -0.508 0.9398)
			(end 0.508 -0.9398)
			(stroke
				(width 0)
				(type default)
			)
			(fill no)
			(layer "F.CrtYd")
		)
		(fp_rect
			(start -0.508 0.9398)
			(end 0.508 -0.9398)
			(stroke
				(width 0)
				(type default)
			)
			(fill no)
			(layer "F.Fab")
		)
		(pad "1" smd custom
			(at 0 -0.4445 90)
			(size 0.1397 0.1397)
			(layers "F.Cu" "F.Mask" "F.Paste")
			(net "P5VB_HDD9_LED")
			(options
				(clearance outline)
				(anchor circle)
			)
			(primitives
				(gr_poly
					(pts
						(arc
							(start -0.1778 -0.2794)
							(mid -0.249642 -0.249642)
							(end -0.2794 -0.1778)
						)
						(arc
							(start -0.2794 0.1778)
							(mid -0.249642 0.249642)
							(end -0.1778 0.2794)
						)
						(arc
							(start 0.1778 0.2794)
							(mid 0.249642 0.249642)
							(end 0.2794 0.1778)
						)
						(arc
							(start 0.2794 -0.1778)
							(mid 0.249642 -0.249642)
							(end 0.1778 -0.2794)
						)
					)
					(width 0)
					(fill yes)
				)
			)
		)
		(pad "2" smd custom
			(at 0 0.4445 90)
			(size 0.1397 0.1397)
			(layers "F.Cu" "F.Mask" "F.Paste")
			(net "DRV_ACT_9")
			(options
				(clearance outline)
				(anchor circle)
			)
			(primitives
				(gr_poly
					(pts
						(arc
							(start -0.1778 -0.2794)
							(mid -0.249642 -0.249642)
							(end -0.2794 -0.1778)
						)
						(arc
							(start -0.2794 0.1778)
							(mid -0.249642 0.249642)
							(end -0.1778 0.2794)
						)
						(arc
							(start 0.1778 0.2794)
							(mid 0.249642 0.249642)
							(end 0.2794 0.1778)
						)
						(arc
							(start 0.2794 -0.1778)
							(mid 0.249642 -0.249642)
							(end 0.1778 -0.2794)
						)
					)
					(width 0)
					(fill yes)
				)
			)
		)
	)
	(footprint ""
		(layer "F.Cu")
		(at 197.116446 -461.679036 90)
		(property "Reference" "R351"
			(at 0 0 90)
			(layer "F.SilkS")
			(hide yes)
			(effects
				(font
					(size 1.27 1.27)
				)
			)
		)
		(property "Value" "0R2J-2-GP"
			(at 0.064008 -3.993896 90)
			(unlocked yes)
			(layer "F.Fab")
			(hide yes)
			(effects
				(font
					(size 1.016 1.016)
					(thickness 0.1524)
				)
			)
		)
		(property "Device Type" "R402H16"
			(at 0.064008 -5.517896 90)
			(unlocked yes)
			(layer "F.Fab")
			(hide yes)
			(effects
				(font
					(size 1.016 1.016)
					(thickness 0.1524)
				)
			)
		)
		(duplicate_pad_numbers_are_jumpers no)
		(fp_line
			(start 0.508 -0.9398)
			(end -0.508 -0.9398)
			(stroke
				(width 0.1524)
				(type default)
			)
			(layer "F.SilkS")
		)
		(fp_line
			(start -0.508 -0.9398)
			(end -0.508 0.9398)
			(stroke
				(width 0.1524)
				(type default)
			)
			(layer "F.SilkS")
		)
		(fp_rect
			(start -0.508 0.9398)
			(end 0.508 -0.9398)
			(stroke
				(width 0)
				(type default)
			)
			(fill no)
			(layer "F.CrtYd")
		)
		(fp_rect
			(start -0.508 0.9398)
			(end 0.508 -0.9398)
			(stroke
				(width 0)
				(type default)
			)
			(fill no)
			(layer "F.Fab")
		)
		(pad "1" smd custom
			(at 0 -0.4445 90)
			(size 0.1397 0.1397)
			(layers "F.Cu" "F.Mask" "F.Paste")
			(net "EEPROM_WP")
			(options
				(clearance outline)
				(anchor circle)
			)
			(primitives
				(gr_poly
					(pts
						(arc
							(start -0.1778 -0.2794)
							(mid -0.249642 -0.249642)
							(end -0.2794 -0.1778)
						)
						(arc
							(start -0.2794 0.1778)
							(mid -0.249642 0.249642)
							(end -0.1778 0.2794)
						)
						(arc
							(start 0.1778 0.2794)
							(mid 0.249642 0.249642)
							(end 0.2794 0.1778)
						)
						(arc
							(start 0.2794 -0.1778)
							(mid 0.249642 -0.249642)
							(end 0.1778 -0.2794)
						)
					)
					(width 0)
					(fill yes)
				)
			)
		)
		(pad "2" smd custom
			(at 0 0.4445 90)
			(size 0.1397 0.1397)
			(layers "F.Cu" "F.Mask" "F.Paste")
			(net "GND")
			(options
				(clearance outline)
				(anchor circle)
			)
			(primitives
				(gr_poly
					(pts
						(arc
							(start -0.1778 -0.2794)
							(mid -0.249642 -0.249642)
							(end -0.2794 -0.1778)
						)
						(arc
							(start -0.2794 0.1778)
							(mid -0.249642 0.249642)
							(end -0.1778 0.2794)
						)
						(arc
							(start 0.1778 0.2794)
							(mid 0.249642 0.249642)
							(end 0.2794 0.1778)
						)
						(arc
							(start 0.2794 -0.1778)
							(mid 0.249642 -0.249642)
							(end 0.1778 -0.2794)
						)
					)
					(width 0)
					(fill yes)
				)
			)
		)
	)
	(footprint ""
		(layer "F.Cu")
		(at 42.600118 -137.510012 180)
		(property "Reference" "U47"
			(at 0 0 180)
			(layer "F.SilkS")
			(hide yes)
			(effects
				(font
					(size 1.27 1.27)
				)
			)
		)
		(property "Value" "TMP75AIDGKR-GP"
			(at -0.1143 -9.1948 180)
			(unlocked yes)
			(layer "F.Fab")
			(hide yes)
			(effects
				(font
					(size 1.016 1.016)
					(thickness 0.1524)
				)
			)
		)
		(property "Device Type" "MSOP8-1H44"
			(at -0.1143 -10.795 180)
			(unlocked yes)
			(layer "F.Fab")
			(hide yes)
			(effects
				(font
					(size 1.016 1.016)
					(thickness 0.1524)
				)
			)
		)
		(duplicate_pad_numbers_are_jumpers no)
		(fp_line
			(start 1.0795 1.016)
			(end 1.0795 -1.016)
			(stroke
				(width 0.1524)
				(type default)
			)
			(layer "F.SilkS")
		)
		(fp_line
			(start 1.0795 -1.016)
			(end -1.9558 -1.016)
			(stroke
				(width 0.1524)
				(type default)
			)
			(layer "F.SilkS")
		)
		(fp_line
			(start -1.4478 -0.0381)
			(end -1.9558 0.4699)
			(stroke
				(width 0.1524)
				(type default)
			)
			(layer "F.SilkS")
		)
		(fp_line
			(start -1.778 1.0922)
			(end -1.778 3.048)
			(stroke
				(width 0.508)
				(type default)
			)
			(layer "F.SilkS")
		)
		(fp_line
			(start -1.9558 1.016)
			(end 1.0795 1.016)
			(stroke
				(width 0.1524)
				(type default)
			)
			(layer "F.SilkS")
		)
		(fp_line
			(start -1.9558 -0.5461)
			(end -1.4478 -0.0381)
			(stroke
				(width 0.1524)
				(type default)
			)
			(layer "F.SilkS")
		)
		(fp_line
			(start -1.9558 -1.016)
			(end -1.9558 1.016)
			(stroke
				(width 0.1524)
				(type default)
			)
			(layer "F.SilkS")
		)
		(fp_poly
			(pts
				(xy -1.1557 -1.016) (xy -1.1557 1.016) (xy 1.1557 1.016) (xy 1.1557 -1.016)
			)
			(stroke
				(width 0)
				(type default)
			)
			(fill yes)
			(layer "F.SilkS")
		)
		(fp_rect
			(start -1.4986 2.4511)
			(end 1.4986 -2.4511)
			(stroke
				(width 0)
				(type default)
			)
			(fill no)
			(layer "F.CrtYd")
		)
		(fp_poly
			(pts
				(xy -2.032 3.302) (xy -2.032 -3.302) (xy 2.032 -3.302) (xy 2.032 -2.1209) (xy 1.4986 -2.1209) (xy 1.4986 -2.4511)
				(xy -1.4986 -2.4511) (xy -1.4986 2.4511) (xy 1.4986 2.4511) (xy 1.4986 -2.1082) (xy 2.032 -2.1082)
				(xy 2.032 3.302)
			)
			(stroke
				(width 0)
				(type default)
			)
			(fill no)
			(layer "F.CrtYd")
		)
		(fp_rect
			(start -2.032 3.302)
			(end 2.032 -3.302)
			(stroke
				(width 0)
				(type default)
			)
			(fill no)
			(layer "F.Fab")
		)
		(pad "1" smd rect
			(at -0.97536 2.05486 180)
			(size 0.3556 1.524)
			(layers "F.Cu" "F.Mask" "F.Paste")
			(net "TMP2_SDA")
		)
		(pad "2" smd rect
			(at -0.32512 2.05486 180)
			(size 0.3556 1.524)
			(layers "F.Cu" "F.Mask" "F.Paste")
			(net "TMP2_SCL")
		)
		(pad "3" smd rect
			(at 0.32512 2.05486 180)
			(size 0.3556 1.524)
			(layers "F.Cu" "F.Mask" "F.Paste")
			(net "I2C_B_TMP2_ALERT")
		)
		(pad "4" smd rect
			(at 0.97536 2.05486 180)
			(size 0.3556 1.524)
			(layers "F.Cu" "F.Mask" "F.Paste")
			(net "GND")
		)
		(pad "5" smd rect
			(at 0.97536 -2.05486 180)
			(size 0.3556 1.524)
			(layers "F.Cu" "F.Mask" "F.Paste")
			(net "I2C_B_TMP2_A2")
		)
		(pad "6" smd rect
			(at 0.32512 -2.05486 180)
			(size 0.3556 1.524)
			(layers "F.Cu" "F.Mask" "F.Paste")
			(net "I2C_B_TMP2_A1")
		)
		(pad "7" smd rect
			(at -0.32512 -2.05486 180)
			(size 0.3556 1.524)
			(layers "F.Cu" "F.Mask" "F.Paste")
			(net "I2C_B_TMP2_A0")
		)
		(pad "8" smd rect
			(at -0.97536 -2.05486 180)
			(size 0.3556 1.524)
			(layers "F.Cu" "F.Mask" "F.Paste")
			(net "P3V3")
		)
	)
	(footprint ""
		(layer "F.Cu")
		(at 191.256412 -85.705696 180)
		(property "Reference" "R168"
			(at 0 0 180)
			(layer "F.SilkS")
			(hide yes)
			(effects
				(font
					(size 1.27 1.27)
				)
			)
		)
		(property "Value" "0R2J-2-GP"
			(at 0.064008 -3.993896 180)
			(unlocked yes)
			(layer "F.Fab")
			(hide yes)
			(effects
				(font
					(size 1.016 1.016)
					(thickness 0.1524)
				)
			)
		)
		(property "Device Type" "R402H16"
			(at 0.064008 -5.517896 180)
			(unlocked yes)
			(layer "F.Fab")
			(hide yes)
			(effects
				(font
					(size 1.016 1.016)
					(thickness 0.1524)
				)
			)
		)
		(duplicate_pad_numbers_are_jumpers no)
		(fp_line
			(start 0.508 -0.9398)
			(end -0.508 -0.9398)
			(stroke
				(width 0.1524)
				(type default)
			)
			(layer "F.SilkS")
		)
		(fp_line
			(start -0.508 -0.9398)
			(end -0.508 0.9398)
			(stroke
				(width 0.1524)
				(type default)
			)
			(layer "F.SilkS")
		)
		(fp_rect
			(start -0.508 0.9398)
			(end 0.508 -0.9398)
			(stroke
				(width 0)
				(type default)
			)
			(fill no)
			(layer "F.CrtYd")
		)
		(fp_rect
			(start -0.508 0.9398)
			(end 0.508 -0.9398)
			(stroke
				(width 0)
				(type default)
			)
			(fill no)
			(layer "F.Fab")
		)
		(pad "1" smd custom
			(at 0 -0.4445 180)
			(size 0.1397 0.1397)
			(layers "F.Cu" "F.Mask" "F.Paste")
			(net "SW_PWR_HDD4")
			(options
				(clearance outline)
				(anchor circle)
			)
			(primitives
				(gr_poly
					(pts
						(arc
							(start -0.1778 -0.2794)
							(mid -0.249642 -0.249642)
							(end -0.2794 -0.1778)
						)
						(arc
							(start -0.2794 0.1778)
							(mid -0.249642 0.249642)
							(end -0.1778 0.2794)
						)
						(arc
							(start 0.1778 0.2794)
							(mid 0.249642 0.249642)
							(end 0.2794 0.1778)
						)
						(arc
							(start 0.2794 -0.1778)
							(mid 0.249642 -0.249642)
							(end 0.1778 -0.2794)
						)
					)
					(width 0)
					(fill yes)
				)
			)
		)
		(pad "2" smd custom
			(at 0 0.4445 180)
			(size 0.1397 0.1397)
			(layers "F.Cu" "F.Mask" "F.Paste")
			(net "SW_PWR_R_HDD4")
			(options
				(clearance outline)
				(anchor circle)
			)
			(primitives
				(gr_poly
					(pts
						(arc
							(start -0.1778 -0.2794)
							(mid -0.249642 -0.249642)
							(end -0.2794 -0.1778)
						)
						(arc
							(start -0.2794 0.1778)
							(mid -0.249642 0.249642)
							(end -0.1778 0.2794)
						)
						(arc
							(start 0.1778 0.2794)
							(mid 0.249642 0.249642)
							(end 0.2794 0.1778)
						)
						(arc
							(start 0.2794 -0.1778)
							(mid 0.249642 -0.249642)
							(end 0.1778 -0.2794)
						)
					)
					(width 0)
					(fill yes)
				)
			)
		)
	)
	(footprint ""
		(layer "F.Cu")
		(at 28.574746 -425.986702)
		(property "Reference" "C267"
			(at 0 0 0)
			(layer "F.SilkS")
			(hide yes)
			(effects
				(font
					(size 1.27 1.27)
				)
			)
		)
		(property "Value" "SC10U16V6KX-2GP"
			(at -0.0762 -5.1308 0)
			(unlocked yes)
			(layer "F.Fab")
			(hide yes)
			(effects
				(font
					(size 1.016 1.016)
					(thickness 0.1524)
				)
			)
		)
		(property "Device Type" "C1206H71"
			(at -0.127 -6.6548 0)
			(unlocked yes)
			(layer "F.Fab")
			(hide yes)
			(effects
				(font
					(size 1.016 1.016)
					(thickness 0.1524)
				)
			)
		)
		(duplicate_pad_numbers_are_jumpers no)
		(fp_line
			(start -1.016 -2.2352)
			(end 1.016 -2.2352)
			(stroke
				(width 0.1524)
				(type default)
			)
			(layer "F.SilkS")
		)
		(fp_line
			(start -1.016 -0.8382)
			(end -1.016 -2.2352)
			(stroke
				(width 0.1524)
				(type default)
			)
			(layer "F.SilkS")
		)
		(fp_line
			(start -1.016 2.2352)
			(end -1.016 0.8382)
			(stroke
				(width 0.1524)
				(type default)
			)
			(layer "F.SilkS")
		)
		(fp_line
			(start 1.016 -2.2352)
			(end 1.016 -0.8382)
			(stroke
				(width 0.1524)
				(type default)
			)
			(layer "F.SilkS")
		)
		(fp_line
			(start 1.016 0.8382)
			(end 1.016 2.2352)
			(stroke
				(width 0.1524)
				(type default)
			)
			(layer "F.SilkS")
		)
		(fp_line
			(start 1.016 2.2352)
			(end -1.016 2.2352)
			(stroke
				(width 0.1524)
				(type default)
			)
			(layer "F.SilkS")
		)
		(fp_rect
			(start -1.0922 2.3114)
			(end 1.0922 -2.3114)
			(stroke
				(width 0)
				(type default)
			)
			(fill no)
			(layer "F.CrtYd")
		)
		(fp_poly
			(pts
				(xy 1.0922 -2.3114) (xy 1.0922 2.3114) (xy -1.0922 2.3114) (xy -1.0922 -2.3114)
			)
			(stroke
				(width 0)
				(type default)
			)
			(fill no)
			(layer "F.Fab")
		)
		(pad "1" smd rect
			(at 0 -1.397)
			(size 1.651 1.27)
			(layers "F.Cu" "F.Mask" "F.Paste")
			(net "P5V_HDD10")
		)
		(pad "2" smd rect
			(at 0 1.397)
			(size 1.651 1.27)
			(layers "F.Cu" "F.Mask" "F.Paste")
			(net "GND")
		)
	)
)
